(kicad_pcb
	(version 20260206)
	(generator "pcbnew")
	(generator_version "10.0")
	(general
		(thickness 1.6)
		(legacy_teardrops no)
	)
	(paper "A4")
	(title_block
		(title "03242023_DA0F0TMBIJ0_F0T_Motherboard_J_brd_V01_OCP.brd")
		(comment 1 "Grand Teton / footprint 1682 of 6105 (U1), pads 4542-4651 of 4677")
	)
	(layers
		(0 "F.Cu" signal "TOP")
		(4 "In1.Cu" signal "GND")
		(6 "In2.Cu" signal "IN1")
		(8 "In3.Cu" signal "GND1")
		(10 "In4.Cu" signal "IN2")
		(12 "In5.Cu" signal "GND2")
		(14 "In6.Cu" signal "IN3")
		(16 "In7.Cu" signal "GND3")
		(18 "In8.Cu" signal "VCC")
		(20 "In9.Cu" signal "VCC1")
		(22 "In10.Cu" signal "GND4")
		(24 "In11.Cu" signal "IN4")
		(26 "In12.Cu" signal "GND5")
		(28 "In13.Cu" signal "IN5")
		(30 "In14.Cu" signal "GND6")
		(32 "In15.Cu" signal "IN6")
		(34 "In16.Cu" signal "GND7")
		(2 "B.Cu" signal "BOTTOM")
		(9 "F.Adhes" user "F.Adhesive")
		(11 "B.Adhes" user "B.Adhesive")
		(13 "F.Paste" user "Package Geometry/Pastemask Top")
		(15 "B.Paste" user "Package Geometry/Pastemask Bottom")
		(5 "F.SilkS" user "Ref Des/Silkscreen Top")
		(7 "B.SilkS" user "Ref Des/Silkscreen Bottom")
		(1 "F.Mask" user "Board Geometry/Soldermask Top")
		(3 "B.Mask" user "Board Geometry/Soldermask Bottom")
		(17 "Dwgs.User" user "User.Drawings")
		(19 "Cmts.User" user "User.Comments")
		(21 "Eco1.User" user "User.Eco1")
		(23 "Eco2.User" user "User.Eco2")
		(25 "Edge.Cuts" user "Board Geometry/Outline")
		(27 "Margin" user)
		(31 "F.CrtYd" user "Package Geometry/Place Bound Top")
		(29 "B.CrtYd" user "Package Geometry/Place Bound Bottom")
		(35 "F.Fab" user "Ref Des/Assembly Top")
		(33 "B.Fab" user "Ref Des/Assembly Bottom")
	)
	(footprint ""
		(layer "F.Cu")
		(at 111.93018 -251.76988 90)
		(property "Reference" "U1"
			(at -74.913236 41.548812 0)
			(unlocked yes)
			(layer "F.SilkS")
			(effects
				(font
					(size 1.6002 1.1938)
					(thickness 0.1524)
				)
				(justify left)
			)
		)
		(property "Value" ""
			(at 0 0 90)
			(layer "F.Fab")
			(effects
				(font
					(size 1.27 1.27)
				)
			)
		)
		(duplicate_pad_numbers_are_jumpers no)
		(pad "U90" smd circle
			(at 36.611306 -19.445732 270)
			(size 0.4318 0.4318)
			(layers "F.Cu" "F.Mask" "F.Paste")
			(net "P5E_CPU1_PE4_RX_DP<3>")
		)
		(pad "V2" smd circle
			(at -36.611306 -19.086068 270)
			(size 0.4318 0.4318)
			(layers "F.Cu" "F.Mask" "F.Paste")
			(net "UPI_CPU1_CPU0_P0P1_DP<4>")
		)
		(pad "V4" smd circle
			(at -34.98342 -19.086068 270)
			(size 0.4318 0.4318)
			(layers "F.Cu" "F.Mask" "F.Paste")
			(net "GND")
		)
		(pad "V6" smd circle
			(at -33.355534 -19.086068 270)
			(size 0.4318 0.4318)
			(layers "F.Cu" "F.Mask" "F.Paste")
			(net "UPI_CPU0_CPU1_P1P0_DN<4>")
		)
		(pad "V8" smd circle
			(at -31.727902 -19.086068 270)
			(size 0.4318 0.4318)
			(layers "F.Cu" "F.Mask" "F.Paste")
			(net "GND")
		)
		(pad "V10" smd circle
			(at -30.100016 -19.086068 270)
			(size 0.4318 0.4318)
			(layers "F.Cu" "F.Mask" "F.Paste")
			(net "P5E_CPU1_PE0_RX_DN<4>")
		)
		(pad "V12" smd circle
			(at -28.472384 -19.086068 270)
			(size 0.4318 0.4318)
			(layers "F.Cu" "F.Mask" "F.Paste")
			(net "GND")
		)
		(pad "V14" smd circle
			(at -26.844498 -19.086068 270)
			(size 0.4318 0.4318)
			(layers "F.Cu" "F.Mask" "F.Paste")
			(net "P5E_CPU1_PE0_TX_DN<3>")
		)
		(pad "V16" smd circle
			(at -25.216612 -19.086068 270)
			(size 0.4318 0.4318)
			(layers "F.Cu" "F.Mask" "F.Paste")
			(net "GND")
		)
		(pad "V18" smd circle
			(at -23.58898 -19.086068 270)
			(size 0.4318 0.4318)
			(layers "F.Cu" "F.Mask" "F.Paste")
			(net "GND")
		)
		(pad "V20" smd circle
			(at -21.961094 -19.086068 270)
			(size 0.4318 0.4318)
			(layers "F.Cu" "F.Mask" "F.Paste")
			(net "GND")
		)
		(pad "V22" smd circle
			(at -20.333462 -19.086068 270)
			(size 0.4318 0.4318)
			(layers "F.Cu" "F.Mask" "F.Paste")
			(net "GND")
		)
		(pad "V24" smd circle
			(at -18.705576 -19.086068 270)
			(size 0.4318 0.4318)
			(layers "F.Cu" "F.Mask" "F.Paste")
			(net "GND")
		)
		(pad "V26" smd circle
			(at -17.07769 -19.086068 270)
			(size 0.4318 0.4318)
			(layers "F.Cu" "F.Mask" "F.Paste")
			(net "GND")
		)
		(pad "V28" smd circle
			(at -15.450058 -19.086068 270)
			(size 0.4318 0.4318)
			(layers "F.Cu" "F.Mask" "F.Paste")
			(net "GND")
		)
		(pad "V30" smd circle
			(at -13.822426 -19.086068 270)
			(size 0.4318 0.4318)
			(layers "F.Cu" "F.Mask" "F.Paste")
			(net "GND")
		)
		(pad "V32" smd circle
			(at -12.19454 -19.086068 270)
			(size 0.4318 0.4318)
			(layers "F.Cu" "F.Mask" "F.Paste")
			(net "GND")
		)
		(pad "V34" smd circle
			(at -10.566654 -19.086068 270)
			(size 0.4318 0.4318)
			(layers "F.Cu" "F.Mask" "F.Paste")
			(net "GND")
		)
		(pad "V36" smd circle
			(at -8.939022 -19.086068 270)
			(size 0.4318 0.4318)
			(layers "F.Cu" "F.Mask" "F.Paste")
			(net "GND")
		)
		(pad "V38" smd circle
			(at -7.311136 -19.086068 270)
			(size 0.4318 0.4318)
			(layers "F.Cu" "F.Mask" "F.Paste")
			(net "GND")
		)
		(pad "V40" smd circle
			(at -5.68325 -19.086068 270)
			(size 0.4318 0.4318)
			(layers "F.Cu" "F.Mask" "F.Paste")
			(net "GND")
		)
		(pad "V42" smd circle
			(at -4.055618 -19.086068 270)
			(size 0.4318 0.4318)
			(layers "F.Cu" "F.Mask" "F.Paste")
			(net "GND")
		)
		(pad "V44" smd circle
			(at -2.427732 -19.086068 270)
			(size 0.4318 0.4318)
			(layers "F.Cu" "F.Mask" "F.Paste")
			(net "GND")
		)
		(pad "V47" smd circle
			(at 1.613916 -18.976086 270)
			(size 0.4318 0.4318)
			(layers "F.Cu" "F.Mask" "F.Paste")
			(net "GND")
		)
		(pad "V49" smd circle
			(at 3.241802 -18.976086 270)
			(size 0.4318 0.4318)
			(layers "F.Cu" "F.Mask" "F.Paste")
			(net "GND")
		)
		(pad "V51" smd circle
			(at 4.869434 -18.976086 270)
			(size 0.4318 0.4318)
			(layers "F.Cu" "F.Mask" "F.Paste")
			(net "GND")
		)
		(pad "V53" smd circle
			(at 6.49732 -18.976086 270)
			(size 0.4318 0.4318)
			(layers "F.Cu" "F.Mask" "F.Paste")
			(net "GND")
		)
		(pad "V55" smd circle
			(at 8.124952 -18.976086 270)
			(size 0.4318 0.4318)
			(layers "F.Cu" "F.Mask" "F.Paste")
			(net "GND")
		)
		(pad "V57" smd circle
			(at 9.752838 -18.976086 270)
			(size 0.4318 0.4318)
			(layers "F.Cu" "F.Mask" "F.Paste")
			(net "GND")
		)
		(pad "V59" smd circle
			(at 11.380724 -18.976086 270)
			(size 0.4318 0.4318)
			(layers "F.Cu" "F.Mask" "F.Paste")
			(net "GND")
		)
		(pad "V61" smd circle
			(at 13.008356 -18.976086 270)
			(size 0.4318 0.4318)
			(layers "F.Cu" "F.Mask" "F.Paste")
			(net "GND")
		)
		(pad "V63" smd circle
			(at 14.635988 -18.976086 270)
			(size 0.4318 0.4318)
			(layers "F.Cu" "F.Mask" "F.Paste")
			(net "GND")
		)
		(pad "V65" smd circle
			(at 16.263874 -18.976086 270)
			(size 0.4318 0.4318)
			(layers "F.Cu" "F.Mask" "F.Paste")
			(net "GND")
		)
		(pad "V67" smd circle
			(at 17.89176 -18.976086 270)
			(size 0.4318 0.4318)
			(layers "F.Cu" "F.Mask" "F.Paste")
			(net "GND")
		)
		(pad "V69" smd circle
			(at 19.519392 -18.976086 270)
			(size 0.4318 0.4318)
			(layers "F.Cu" "F.Mask" "F.Paste")
			(net "GND")
		)
		(pad "V71" smd circle
			(at 21.147278 -18.976086 270)
			(size 0.4318 0.4318)
			(layers "F.Cu" "F.Mask" "F.Paste")
			(net "GND")
		)
		(pad "V73" smd circle
			(at 22.77491 -18.976086 270)
			(size 0.4318 0.4318)
			(layers "F.Cu" "F.Mask" "F.Paste")
			(net "GND")
		)
		(pad "V75" smd circle
			(at 24.402796 -18.976086 270)
			(size 0.4318 0.4318)
			(layers "F.Cu" "F.Mask" "F.Paste")
			(net "GND")
		)
		(pad "V77" smd circle
			(at 26.030682 -18.976086 270)
			(size 0.4318 0.4318)
			(layers "F.Cu" "F.Mask" "F.Paste")
			(net "GND")
		)
		(pad "V79" smd circle
			(at 27.658314 -18.976086 270)
			(size 0.4318 0.4318)
			(layers "F.Cu" "F.Mask" "F.Paste")
			(net "GND")
		)
		(pad "V81" smd circle
			(at 29.2862 -18.976086 270)
			(size 0.4318 0.4318)
			(layers "F.Cu" "F.Mask" "F.Paste")
			(net "UPI_CPU1_CPU0_P2P2_DP<7>")
		)
		(pad "V83" smd circle
			(at 30.914086 -18.976086 270)
			(size 0.4318 0.4318)
			(layers "F.Cu" "F.Mask" "F.Paste")
			(net "UPI_CPU1_CPU0_P2P2_DN<8>")
		)
		(pad "V85" smd circle
			(at 32.541718 -18.976086 270)
			(size 0.4318 0.4318)
			(layers "F.Cu" "F.Mask" "F.Paste")
			(net "P5E_CPU1_PE4_TX_DP<3>")
		)
		(pad "V87" smd circle
			(at 34.169604 -18.976086 270)
			(size 0.4318 0.4318)
			(layers "F.Cu" "F.Mask" "F.Paste")
			(net "GND")
		)
		(pad "V89" smd circle
			(at 35.797236 -18.976086 270)
			(size 0.4318 0.4318)
			(layers "F.Cu" "F.Mask" "F.Paste")
			(net "P5E_CPU1_PE4_RX_DN<3>")
		)
		(pad "V91" smd oval
			(at 37.425122 -18.976086)
			(size 0.381 0.4826)
			(drill
				(offset 0 -0.0508)
			)
			(layers "F.Cu" "F.Mask" "F.Paste")
			(net "GND")
		)
		(pad "W1" smd oval
			(at -37.425122 -18.615914 180)
			(size 0.381 0.4826)
			(drill
				(offset 0 -0.0508)
			)
			(layers "F.Cu" "F.Mask" "F.Paste")
			(net "GND")
		)
		(pad "W3" smd circle
			(at -35.797236 -18.615914 270)
			(size 0.4318 0.4318)
			(layers "F.Cu" "F.Mask" "F.Paste")
			(net "UPI_CPU1_CPU0_P0P1_DP<5>")
		)
		(pad "W5" smd circle
			(at -34.169604 -18.615914 270)
			(size 0.4318 0.4318)
			(layers "F.Cu" "F.Mask" "F.Paste")
			(net "GND")
		)
		(pad "W7" smd circle
			(at -32.541718 -18.615914 270)
			(size 0.4318 0.4318)
			(layers "F.Cu" "F.Mask" "F.Paste")
			(net "UPI_CPU0_CPU1_P1P0_DP<4>")
		)
		(pad "W9" smd circle
			(at -30.914086 -18.615914 270)
			(size 0.4318 0.4318)
			(layers "F.Cu" "F.Mask" "F.Paste")
			(net "GND")
		)
		(pad "W11" smd circle
			(at -29.2862 -18.615914 270)
			(size 0.4318 0.4318)
			(layers "F.Cu" "F.Mask" "F.Paste")
			(net "P5E_CPU1_PE0_RX_DP<4>")
		)
		(pad "W13" smd circle
			(at -27.658314 -18.615914 270)
			(size 0.4318 0.4318)
			(layers "F.Cu" "F.Mask" "F.Paste")
			(net "GND")
		)
		(pad "W15" smd circle
			(at -26.030682 -18.615914 270)
			(size 0.4318 0.4318)
			(layers "F.Cu" "F.Mask" "F.Paste")
			(net "P5E_CPU1_PE0_TX_DP<3>")
		)
		(pad "W17" smd circle
			(at -24.402796 -18.615914 270)
			(size 0.4318 0.4318)
			(layers "F.Cu" "F.Mask" "F.Paste")
			(net "NC_CPU1_HBM1_VIEWDIG0")
		)
		(pad "W19" smd circle
			(at -22.77491 -18.615914 270)
			(size 0.4318 0.4318)
			(layers "F.Cu" "F.Mask" "F.Paste")
			(net "M_C_CPU1_SB_DQ<23>")
		)
		(pad "W21" smd circle
			(at -21.147278 -18.615914 270)
			(size 0.4318 0.4318)
			(layers "F.Cu" "F.Mask" "F.Paste")
			(net "M_C_CPU1_SB_DQS_DN<7>")
		)
		(pad "W23" smd circle
			(at -19.519392 -18.615914 270)
			(size 0.4318 0.4318)
			(layers "F.Cu" "F.Mask" "F.Paste")
			(net "M_C_CPU1_SB_DQ<18>")
		)
		(pad "W25" smd circle
			(at -17.89176 -18.615914 270)
			(size 0.4318 0.4318)
			(layers "F.Cu" "F.Mask" "F.Paste")
			(net "M_B_CPU1_SB_DQ<7>")
		)
		(pad "W27" smd circle
			(at -16.263874 -18.615914 270)
			(size 0.4318 0.4318)
			(layers "F.Cu" "F.Mask" "F.Paste")
			(net "M_B_CPU1_SB_DQS_DN<5>")
		)
		(pad "W29" smd circle
			(at -14.635988 -18.615914 270)
			(size 0.4318 0.4318)
			(layers "F.Cu" "F.Mask" "F.Paste")
			(net "M_B_CPU1_SB_DQ<2>")
		)
		(pad "W31" smd circle
			(at -13.008356 -18.615914 270)
			(size 0.4318 0.4318)
			(layers "F.Cu" "F.Mask" "F.Paste")
			(net "M_C_CPU1_SB_CB<3>")
		)
		(pad "W33" smd circle
			(at -11.380724 -18.615914 270)
			(size 0.4318 0.4318)
			(layers "F.Cu" "F.Mask" "F.Paste")
			(net "M_C_CPU1_SB_DQS_DN<4>")
		)
		(pad "W35" smd circle
			(at -9.752838 -18.615914 270)
			(size 0.4318 0.4318)
			(layers "F.Cu" "F.Mask" "F.Paste")
			(net "M_C_CPU1_SB_CB<6>")
		)
		(pad "W37" smd circle
			(at -8.124952 -18.615914 270)
			(size 0.4318 0.4318)
			(layers "F.Cu" "F.Mask" "F.Paste")
			(net "M_C_CPU1_SB_CS_N<3>")
		)
		(pad "W39" smd circle
			(at -6.49732 -18.615914 270)
			(size 0.4318 0.4318)
			(layers "F.Cu" "F.Mask" "F.Paste")
			(net "GND")
		)
		(pad "W41" smd circle
			(at -4.869434 -18.615914 270)
			(size 0.4318 0.4318)
			(layers "F.Cu" "F.Mask" "F.Paste")
			(net "M_C_CPU1_SB_CA<3>")
		)
		(pad "W43" smd circle
			(at -3.241802 -18.615914 270)
			(size 0.4318 0.4318)
			(layers "F.Cu" "F.Mask" "F.Paste")
			(net "M_B_CPU1_SA_PAR")
		)
		(pad "W45" smd circle
			(at -1.613916 -18.615914 270)
			(size 0.4318 0.4318)
			(layers "F.Cu" "F.Mask" "F.Paste")
			(net "M_B_CPU1_CLK_DN<1>")
		)
		(pad "W48" smd circle
			(at 2.427732 -18.505932 270)
			(size 0.4318 0.4318)
			(layers "F.Cu" "F.Mask" "F.Paste")
			(net "M_C_CPU1_SB_CA<0>")
		)
		(pad "W50" smd circle
			(at 4.055618 -18.505932 270)
			(size 0.4318 0.4318)
			(layers "F.Cu" "F.Mask" "F.Paste")
			(net "M_C_CPU1_SA_CA<5>")
		)
		(pad "W52" smd circle
			(at 5.68325 -18.505932 270)
			(size 0.4318 0.4318)
			(layers "F.Cu" "F.Mask" "F.Paste")
			(net "GND")
		)
		(pad "W54" smd circle
			(at 7.311136 -18.505932 270)
			(size 0.4318 0.4318)
			(layers "F.Cu" "F.Mask" "F.Paste")
			(net "M_C_CPU1_SA_CS_N<2>")
		)
		(pad "W56" smd circle
			(at 8.939022 -18.505932 270)
			(size 0.4318 0.4318)
			(layers "F.Cu" "F.Mask" "F.Paste")
			(net "M_B_CPU1_SA_DQ<31>")
		)
		(pad "W58" smd circle
			(at 10.566654 -18.505932 270)
			(size 0.4318 0.4318)
			(layers "F.Cu" "F.Mask" "F.Paste")
			(net "M_B_CPU1_SA_DQS_DP<8>")
		)
		(pad "W60" smd circle
			(at 12.19454 -18.505932 270)
			(size 0.4318 0.4318)
			(layers "F.Cu" "F.Mask" "F.Paste")
			(net "M_B_CPU1_SA_DQ<26>")
		)
		(pad "W62" smd circle
			(at 13.822426 -18.505932 270)
			(size 0.4318 0.4318)
			(layers "F.Cu" "F.Mask" "F.Paste")
			(net "M_C_CPU1_SA_DQ<23>")
		)
		(pad "W64" smd circle
			(at 15.450058 -18.505932 270)
			(size 0.4318 0.4318)
			(layers "F.Cu" "F.Mask" "F.Paste")
			(net "M_C_CPU1_SA_DQS_DP<7>")
		)
		(pad "W66" smd circle
			(at 17.07769 -18.505932 270)
			(size 0.4318 0.4318)
			(layers "F.Cu" "F.Mask" "F.Paste")
			(net "M_C_CPU1_SA_DQ<18>")
		)
		(pad "W68" smd circle
			(at 18.705576 -18.505932 270)
			(size 0.4318 0.4318)
			(layers "F.Cu" "F.Mask" "F.Paste")
			(net "M_B_CPU1_SA_DQ<15>")
		)
		(pad "W70" smd circle
			(at 20.333462 -18.505932 270)
			(size 0.4318 0.4318)
			(layers "F.Cu" "F.Mask" "F.Paste")
			(net "M_B_CPU1_SA_DQS_DP<6>")
		)
		(pad "W72" smd circle
			(at 21.961094 -18.505932 270)
			(size 0.4318 0.4318)
			(layers "F.Cu" "F.Mask" "F.Paste")
			(net "M_B_CPU1_SA_DQ<10>")
		)
		(pad "W74" smd circle
			(at 23.58898 -18.505932 270)
			(size 0.4318 0.4318)
			(layers "F.Cu" "F.Mask" "F.Paste")
			(net "M_C_CPU1_SA_DQ<7>")
		)
		(pad "W76" smd circle
			(at 25.216612 -18.505932 270)
			(size 0.4318 0.4318)
			(layers "F.Cu" "F.Mask" "F.Paste")
			(net "M_C_CPU1_SA_DQS_DN<5>")
		)
		(pad "W78" smd circle
			(at 26.844498 -18.505932 270)
			(size 0.4318 0.4318)
			(layers "F.Cu" "F.Mask" "F.Paste")
			(net "M_C_CPU1_SA_DQ<2>")
		)
		(pad "W80" smd circle
			(at 28.472384 -18.505932 270)
			(size 0.4318 0.4318)
			(layers "F.Cu" "F.Mask" "F.Paste")
			(net "PVCCFA_EHV_FIVRA_CPU1")
		)
		(pad "W82" smd circle
			(at 30.100016 -18.505932 270)
			(size 0.4318 0.4318)
			(layers "F.Cu" "F.Mask" "F.Paste")
			(net "UPI_CPU1_CPU0_P2P2_DP<9>")
		)
		(pad "W84" smd circle
			(at 31.727902 -18.505932 270)
			(size 0.4318 0.4318)
			(layers "F.Cu" "F.Mask" "F.Paste")
			(net "GND")
		)
		(pad "W86" smd circle
			(at 33.355534 -18.505932 270)
			(size 0.4318 0.4318)
			(layers "F.Cu" "F.Mask" "F.Paste")
			(net "P5E_CPU1_PE4_TX_DN<4>")
		)
		(pad "W88" smd circle
			(at 34.98342 -18.505932 270)
			(size 0.4318 0.4318)
			(layers "F.Cu" "F.Mask" "F.Paste")
			(net "GND")
		)
		(pad "W90" smd circle
			(at 36.611306 -18.505932 270)
			(size 0.4318 0.4318)
			(layers "F.Cu" "F.Mask" "F.Paste")
			(net "P5E_CPU1_PE4_RX_DP<4>")
		)
		(pad "Y2" smd circle
			(at -36.611306 -18.146268 270)
			(size 0.4318 0.4318)
			(layers "F.Cu" "F.Mask" "F.Paste")
			(net "UPI_CPU1_CPU0_P0P1_DN<5>")
		)
		(pad "Y4" smd circle
			(at -34.98342 -18.146268 270)
			(size 0.4318 0.4318)
			(layers "F.Cu" "F.Mask" "F.Paste")
			(net "GND")
		)
		(pad "Y6" smd circle
			(at -33.355534 -18.146268 270)
			(size 0.4318 0.4318)
			(layers "F.Cu" "F.Mask" "F.Paste")
			(net "UPI_CPU0_CPU1_P1P0_DP<5>")
		)
		(pad "Y8" smd circle
			(at -31.727902 -18.146268 270)
			(size 0.4318 0.4318)
			(layers "F.Cu" "F.Mask" "F.Paste")
			(net "GND")
		)
		(pad "Y10" smd circle
			(at -30.100016 -18.146268 270)
			(size 0.4318 0.4318)
			(layers "F.Cu" "F.Mask" "F.Paste")
			(net "P5E_CPU1_PE0_RX_DP<5>")
		)
		(pad "Y12" smd circle
			(at -28.472384 -18.146268 270)
			(size 0.4318 0.4318)
			(layers "F.Cu" "F.Mask" "F.Paste")
			(net "GND")
		)
		(pad "Y14" smd circle
			(at -26.844498 -18.146268 270)
			(size 0.4318 0.4318)
			(layers "F.Cu" "F.Mask" "F.Paste")
			(net "P5E_CPU1_PE0_TX_DP<4>")
		)
		(pad "Y16" smd circle
			(at -25.216612 -18.146268 270)
			(size 0.4318 0.4318)
			(layers "F.Cu" "F.Mask" "F.Paste")
			(net "GND")
		)
		(pad "Y18" smd circle
			(at -23.58898 -18.146268 270)
			(size 0.4318 0.4318)
			(layers "F.Cu" "F.Mask" "F.Paste")
			(net "GND")
		)
		(pad "Y20" smd circle
			(at -21.961094 -18.146268 270)
			(size 0.4318 0.4318)
			(layers "F.Cu" "F.Mask" "F.Paste")
			(net "M_C_CPU1_SB_DQ<22>")
		)
		(pad "Y22" smd circle
			(at -20.333462 -18.146268 270)
			(size 0.4318 0.4318)
			(layers "F.Cu" "F.Mask" "F.Paste")
			(net "M_C_CPU1_SB_DQ<19>")
		)
		(pad "Y24" smd circle
			(at -18.705576 -18.146268 270)
			(size 0.4318 0.4318)
			(layers "F.Cu" "F.Mask" "F.Paste")
			(net "GND")
		)
		(pad "Y26" smd circle
			(at -17.07769 -18.146268 270)
			(size 0.4318 0.4318)
			(layers "F.Cu" "F.Mask" "F.Paste")
			(net "M_B_CPU1_SB_DQ<6>")
		)
		(pad "Y28" smd circle
			(at -15.450058 -18.146268 270)
			(size 0.4318 0.4318)
			(layers "F.Cu" "F.Mask" "F.Paste")
			(net "M_B_CPU1_SB_DQ<3>")
		)
		(pad "Y30" smd circle
			(at -13.822426 -18.146268 270)
			(size 0.4318 0.4318)
			(layers "F.Cu" "F.Mask" "F.Paste")
			(net "GND")
		)
		(pad "Y32" smd circle
			(at -12.19454 -18.146268 270)
			(size 0.4318 0.4318)
			(layers "F.Cu" "F.Mask" "F.Paste")
			(net "M_C_CPU1_SB_CB<2>")
		)
		(pad "Y34" smd circle
			(at -10.566654 -18.146268 270)
			(size 0.4318 0.4318)
			(layers "F.Cu" "F.Mask" "F.Paste")
			(net "M_C_CPU1_SB_CB<7>")
		)
		(pad "Y36" smd circle
			(at -8.939022 -18.146268 270)
			(size 0.4318 0.4318)
			(layers "F.Cu" "F.Mask" "F.Paste")
			(net "GND")
		)
		(pad "Y38" smd circle
			(at -7.311136 -18.146268 270)
			(size 0.4318 0.4318)
			(layers "F.Cu" "F.Mask" "F.Paste")
			(net "M_C_CPU1_SB_CS_N<2>")
		)
	)
)
